# T6G (Grand Teton) — schematic netlist excerpt (pin names and nets, part order shuffled) for the footprints in the layout excerpt that follows; sources: Cadence DE-HDL packaged netlist, KiCad conversion of 04192023_DAF0TMB3IC0_F0TG_MB_C_brd_V02_OCP.brd

R3925  Q_RES  1K 1% CHIP  pkg 0402LF  page 262 : A = IRQ_SML1_PMBUS_ALERT ; B = P3V3_AUX
PC150  Q_CAP  22UF 16V 20% X6S  pkg C0805  page 226 : A = SW_P12V_AUX_PVDD18_S5_P1_FLT ; B = GND
R3273  Q_RES  68K 1% EMPTY  pkg 0402LF  page 111 : A = FM_P2E_FGA ; B = GND

(kicad_pcb
	(version 20260206)
	(generator "pcbnew")
	(generator_version "10.0")
	(general
		(thickness 1.6)
		(legacy_teardrops no)
	)
	(paper "A4")
	(title_block
		(title "04192023_DAF0TMB3IC0_F0TG_MB_C_brd_V02_OCP.brd")
		(comment 1 "Grand Teton / footprints 3781-3783 of 8354")
	)
	(layers
		(0 "F.Cu" signal "TOP")
		(4 "In1.Cu" signal "GND")
		(6 "In2.Cu" signal "IN1")
		(8 "In3.Cu" signal "GND1")
		(10 "In4.Cu" signal "IN2")
		(12 "In5.Cu" signal "GND2")
		(14 "In6.Cu" signal "IN3")
		(16 "In7.Cu" signal "GND3")
		(18 "In8.Cu" signal "VCC")
		(20 "In9.Cu" signal "VCC1")
		(22 "In10.Cu" signal "GND4")
		(24 "In11.Cu" signal "IN4")
		(26 "In12.Cu" signal "GND5")
		(28 "In13.Cu" signal "IN5")
		(30 "In14.Cu" signal "GND6")
		(32 "In15.Cu" signal "IN6")
		(34 "In16.Cu" signal "GND7")
		(2 "B.Cu" signal "BOTTOM")
		(9 "F.Adhes" user "F.Adhesive")
		(11 "B.Adhes" user "B.Adhesive")
		(13 "F.Paste" user "Package Geometry/Pastemask Top")
		(15 "B.Paste" user "Package Geometry/Pastemask Bottom")
		(5 "F.SilkS" user "Ref Des/Silkscreen Top")
		(7 "B.SilkS" user "Ref Des/Silkscreen Bottom")
		(1 "F.Mask" user "Board Geometry/Soldermask Top")
		(3 "B.Mask" user "Board Geometry/Soldermask Bottom")
		(17 "Dwgs.User" user "User.Drawings")
		(19 "Cmts.User" user "User.Comments")
		(21 "Eco1.User" user "User.Eco1")
		(23 "Eco2.User" user "User.Eco2")
		(25 "Edge.Cuts" user "Board Geometry/Outline")
		(27 "Margin" user)
		(31 "F.CrtYd" user "Package Geometry/Place Bound Top")
		(29 "B.CrtYd" user "Package Geometry/Place Bound Bottom")
		(35 "F.Fab" user "Ref Des/Assembly Top")
		(33 "B.Fab" user "Ref Des/Assembly Bottom")
	)
	(footprint ""
		(layer "F.Cu")
		(at 182.14594 -406.659842 90)
		(property "Reference" "R3925"
			(at 0 0 90)
			(layer "F.SilkS")
			(hide yes)
			(effects
				(font
					(size 1.27 1.27)
				)
			)
		)
		(property "Value" ""
			(at 0 0 90)
			(layer "F.Fab")
			(effects
				(font
					(size 1.27 1.27)
				)
			)
		)
		(duplicate_pad_numbers_are_jumpers no)
		(fp_line
			(start 0.7874 -0.4064)
			(end 0.7874 0.4064)
			(stroke
				(width 0.1524)
				(type default)
			)
			(layer "F.SilkS")
		)
		(fp_line
			(start -0.7874 -0.4064)
			(end 0.7874 -0.4064)
			(stroke
				(width 0.1524)
				(type default)
			)
			(layer "F.SilkS")
		)
		(fp_line
			(start 0.7874 0.4064)
			(end -0.7874 0.4064)
			(stroke
				(width 0.1524)
				(type default)
			)
			(layer "F.SilkS")
		)
		(fp_line
			(start -0.7874 0.4064)
			(end -0.7874 -0.4064)
			(stroke
				(width 0.1524)
				(type default)
			)
			(layer "F.SilkS")
		)
		(fp_line
			(start -0.12065 -0.305054)
			(end -0.12065 -0.2794)
			(stroke
				(width 0.1)
				(type default)
			)
			(layer "F.Fab")
		)
		(fp_line
			(start -0.67945 -0.305054)
			(end -0.12065 -0.305054)
			(stroke
				(width 0.1)
				(type default)
			)
			(layer "F.Fab")
		)
		(fp_line
			(start 0.67945 -0.3048)
			(end 0.67945 0.3048)
			(stroke
				(width 0.1)
				(type default)
			)
			(layer "F.Fab")
		)
		(fp_line
			(start 0.12065 -0.3048)
			(end 0.67945 -0.3048)
			(stroke
				(width 0.1)
				(type default)
			)
			(layer "F.Fab")
		)
		(fp_line
			(start 0.12065 -0.2794)
			(end 0.12065 -0.3048)
			(stroke
				(width 0.1)
				(type default)
			)
			(layer "F.Fab")
		)
		(fp_line
			(start -0.12065 -0.2794)
			(end 0.12065 -0.2794)
			(stroke
				(width 0.1)
				(type default)
			)
			(layer "F.Fab")
		)
		(fp_line
			(start 0.120396 0.2794)
			(end -0.12065 0.2794)
			(stroke
				(width 0.1)
				(type default)
			)
			(layer "F.Fab")
		)
		(fp_line
			(start -0.12065 0.2794)
			(end -0.12065 0.3048)
			(stroke
				(width 0.1)
				(type default)
			)
			(layer "F.Fab")
		)
		(fp_line
			(start 0.67945 0.3048)
			(end 0.120396 0.3048)
			(stroke
				(width 0.1)
				(type default)
			)
			(layer "F.Fab")
		)
		(fp_line
			(start 0.120396 0.3048)
			(end 0.120396 0.2794)
			(stroke
				(width 0.1)
				(type default)
			)
			(layer "F.Fab")
		)
		(fp_line
			(start -0.12065 0.3048)
			(end -0.67945 0.3048)
			(stroke
				(width 0.1)
				(type default)
			)
			(layer "F.Fab")
		)
		(fp_line
			(start -0.67945 0.3048)
			(end -0.67945 -0.305054)
			(stroke
				(width 0.1)
				(type default)
			)
			(layer "F.Fab")
		)
		(pad "1" smd circle
			(at -0.40005 0 90)
			(size 0 0)
			(layers "F.Cu" "F.Mask" "F.Paste")
			(net "IRQ_SML1_PMBUS_ALERT")
		)
		(pad "2" smd circle
			(at 0.40005 0 90)
			(size 0 0)
			(layers "F.Cu" "F.Mask" "F.Paste")
			(net "P3V3_AUX")
		)
	)
	(footprint ""
		(layer "F.Cu")
		(at 75.219306 -152.990804 90)
		(property "Reference" "PC150"
			(at 0 0 90)
			(layer "F.SilkS")
			(hide yes)
			(effects
				(font
					(size 1.27 1.27)
				)
			)
		)
		(property "Value" ""
			(at 0 0 90)
			(layer "F.Fab")
			(effects
				(font
					(size 1.27 1.27)
				)
			)
		)
		(duplicate_pad_numbers_are_jumpers no)
		(fp_line
			(start 1.524 -0.762)
			(end 1.524 0.762)
			(stroke
				(width 0.1524)
				(type default)
			)
			(layer "F.SilkS")
		)
		(fp_line
			(start -1.524 -0.762)
			(end 1.524 -0.762)
			(stroke
				(width 0.1524)
				(type default)
			)
			(layer "F.SilkS")
		)
		(fp_line
			(start 1.524 0.762)
			(end -1.524 0.762)
			(stroke
				(width 0.1524)
				(type default)
			)
			(layer "F.SilkS")
		)
		(fp_line
			(start -1.524 0.762)
			(end -1.524 -0.762)
			(stroke
				(width 0.1524)
				(type default)
			)
			(layer "F.SilkS")
		)
		(fp_line
			(start 1.1049 -0.724916)
			(end -1.1049 -0.724916)
			(stroke
				(width 0.1)
				(type default)
			)
			(layer "F.Fab")
		)
		(fp_line
			(start -1.1049 -0.724916)
			(end -1.1049 0.724916)
			(stroke
				(width 0.1)
				(type default)
			)
			(layer "F.Fab")
		)
		(fp_line
			(start 1.1049 0.724916)
			(end 1.1049 -0.724916)
			(stroke
				(width 0.1)
				(type default)
			)
			(layer "F.Fab")
		)
		(fp_line
			(start -1.1049 0.724916)
			(end 1.1049 0.724916)
			(stroke
				(width 0.1)
				(type default)
			)
			(layer "F.Fab")
		)
		(pad "1" smd rect
			(at -0.889 0 270)
			(size 1.016 1.27)
			(layers "F.Cu" "F.Mask" "F.Paste")
			(net "SW_P12V_AUX_PVDD18_S5_P1_FLT")
		)
		(pad "2" smd rect
			(at 0.889 0 270)
			(size 1.016 1.27)
			(layers "F.Cu" "F.Mask" "F.Paste")
			(net "GND")
		)
	)
	(footprint ""
		(layer "F.Cu")
		(at 32.601662 -419.249098 -90)
		(property "Reference" "R3273"
			(at 0 0 270)
			(layer "F.SilkS")
			(hide yes)
			(effects
				(font
					(size 1.27 1.27)
				)
			)
		)
		(property "Value" ""
			(at 0 0 270)
			(layer "F.Fab")
			(effects
				(font
					(size 1.27 1.27)
				)
			)
		)
		(duplicate_pad_numbers_are_jumpers no)
		(fp_line
			(start -0.7874 0.4064)
			(end -0.7874 -0.4064)
			(stroke
				(width 0.1524)
				(type default)
			)
			(layer "F.SilkS")
		)
		(fp_line
			(start 0.7874 0.4064)
			(end -0.7874 0.4064)
			(stroke
				(width 0.1524)
				(type default)
			)
			(layer "F.SilkS")
		)
		(fp_line
			(start -0.7874 -0.4064)
			(end 0.7874 -0.4064)
			(stroke
				(width 0.1524)
				(type default)
			)
			(layer "F.SilkS")
		)
		(fp_line
			(start 0.7874 -0.4064)
			(end 0.7874 0.4064)
			(stroke
				(width 0.1524)
				(type default)
			)
			(layer "F.SilkS")
		)
		(fp_line
			(start -0.67945 0.3048)
			(end -0.67945 -0.305054)
			(stroke
				(width 0.1)
				(type default)
			)
			(layer "F.Fab")
		)
		(fp_line
			(start -0.12065 0.3048)
			(end -0.67945 0.3048)
			(stroke
				(width 0.1)
				(type default)
			)
			(layer "F.Fab")
		)
		(fp_line
			(start 0.120396 0.3048)
			(end 0.120396 0.2794)
			(stroke
				(width 0.1)
				(type default)
			)
			(layer "F.Fab")
		)
		(fp_line
			(start 0.67945 0.3048)
			(end 0.120396 0.3048)
			(stroke
				(width 0.1)
				(type default)
			)
			(layer "F.Fab")
		)
		(fp_line
			(start -0.12065 0.2794)
			(end -0.12065 0.3048)
			(stroke
				(width 0.1)
				(type default)
			)
			(layer "F.Fab")
		)
		(fp_line
			(start 0.120396 0.2794)
			(end -0.12065 0.2794)
			(stroke
				(width 0.1)
				(type default)
			)
			(layer "F.Fab")
		)
		(fp_line
			(start -0.12065 -0.2794)
			(end 0.12065 -0.2794)
			(stroke
				(width 0.1)
				(type default)
			)
			(layer "F.Fab")
		)
		(fp_line
			(start 0.12065 -0.2794)
			(end 0.12065 -0.3048)
			(stroke
				(width 0.1)
				(type default)
			)
			(layer "F.Fab")
		)
		(fp_line
			(start 0.12065 -0.3048)
			(end 0.67945 -0.3048)
			(stroke
				(width 0.1)
				(type default)
			)
			(layer "F.Fab")
		)
		(fp_line
			(start 0.67945 -0.3048)
			(end 0.67945 0.3048)
			(stroke
				(width 0.1)
				(type default)
			)
			(layer "F.Fab")
		)
		(fp_line
			(start -0.67945 -0.305054)
			(end -0.12065 -0.305054)
			(stroke
				(width 0.1)
				(type default)
			)
			(layer "F.Fab")
		)
		(fp_line
			(start -0.12065 -0.305054)
			(end -0.12065 -0.2794)
			(stroke
				(width 0.1)
				(type default)
			)
			(layer "F.Fab")
		)
		(pad "1" smd circle
			(at -0.40005 0 270)
			(size 0 0)
			(layers "F.Cu" "F.Mask" "F.Paste")
			(net "FM_P2E_FGA")
		)
		(pad "2" smd circle
			(at 0.40005 0 270)
			(size 0 0)
			(layers "F.Cu" "F.Mask" "F.Paste")
			(net "GND")
		)
	)
)
